#ISCELL
  cls sheet_a1 *
  *
#ISCELL
  cls offpage_bi *
  page161_i100
#ISCELL
  cls offpage_bi *
  page161_i104
#ISCELL
  cls gnd_sg *
  page161_i136
#ISCELL
  cls offpage_out *
  page161_i139
#CELL
  passive resistor *
  page161_i140
#ISCELL
  cls offpage_out *
  page161_i143
#ISCELL
  cls offpage_in *
  page161_i16
#ISCELL
  cls offpage_in *
  page161_i17
#ISCELL
  cls offpage_bi *
  page161_i19
#CELL
  pld xc7a200t_2fbg484c_fbg484 *
  page161_i2
#CELL
  passive resistor *
  page161_i200
#CELL
  passive resistor *
  page161_i201
#ISCELL
  cls offpage_in *
  page161_i208
#ISCELL
  cls offpage_in *
  page161_i209
#ISCELL
  cls offpage_bi *
  page161_i224
#ISCELL
  cls offpage_out *
  page161_i225
#ISCELL
  cls offpage_out *
  page161_i226
#ISCELL
  cls offpage_bi *
  page161_i234
#ISCELL
  cls offpage_out *
  page161_i235
#ISCELL
  cls offpage_out *
  page161_i236
#ISCELL
  cls offpage_out *
  page161_i237
#ISCELL
  cls gnd_sg *
  page161_i238
#CELL
  passive resistor *
  page161_i239
#CELL
  passive resistor *
  page161_i240
#CELL
  passive resistor *
  page161_i241
#CELL
  passive resistor *
  page161_i242
#CELL
  passive resistor *
  page161_i244
#ISCELL
  cls gnd_sg *
  page161_i245
#CELL
  passive resistor *
  page161_i246
#CELL
  passive resistor *
  page161_i247
#ISCELL
  cls vcc *
  page161_i248
#ISCELL
  cls vcc *
  page161_i249
#ISCELL
  cls gnd_sg *
  page161_i250
#CELL
  passive resistor *
  page161_i251
#CELL
  passive resistor *
  page161_i252
#CELL
  passive resistor *
  page161_i253
#ISCELL
  cls offpage_bi *
  page161_i254
#ISCELL
  cls offpage_bi *
  page161_i255
#ISCELL
  cls offpage_bi *
  page161_i256
#ISCELL
  cls offpage_bi *
  page161_i257
#CELL
  passive resistor *
  page161_i258
#CELL
  passive resistor *
  page161_i259
#CELL
  passive resistor *
  page161_i260
#CELL
  passive resistor *
  page161_i261
#ISCELL
  cls offpage_out *
  page161_i262
#CELL
  passive resistor *
  page161_i263
#ISCELL
  cls offpage_in *
  page161_i27
#ISCELL
  cls offpage_out *
  page161_i28
#ISCELL
  cls offpage_in *
  page161_i34
#ISCELL
  cls offpage_out *
  page161_i35
#ISCELL
  cls offpage_in *
  page161_i36
#ISCELL
  cls offpage_out *
  page161_i37
#ISCELL
  cls offpage_in *
  page161_i38
#ISCELL
  cls offpage_out *
  page161_i39
#ISCELL
  cls offpage_out *
  page161_i42
#ISCELL
  cls offpage_in *
  page161_i43
#ISCELL
  cls offpage_in *
  page161_i44
#ISCELL
  cls offpage_out *
  page161_i54
#ISCELL
  cls offpage_in *
  page161_i55
#ISCELL
  cls offpage_in *
  page161_i60
#ISCELL
  cls offpage_out *
  page161_i61
#ISCELL
  cls offpage_out *
  page161_i62
#ISCELL
  cls offpage_bi *
  page161_i70
#ISCELL
  cls offpage_out *
  page161_i9
